# SCM (Grand Teton) — schematic netlist excerpt (pin names and nets, part order shuffled) for the footprints in the layout excerpt that follows; sources: Cadence DE-HDL packaged netlist, KiCad conversion of 12092022_DA0F0TMDCD0_F0T_Management_Board_D_brd_V3_OCP.brd

C145  Q_CAP  1UF 25V 10% X6S  pkg C0402  page 41 : A = P3V3_AUX ; B = GND
R143  Q_RES  33.2 1% CHIP  pkg 0402LF  page 12 : A = SMB_BMC_MM6_R_SDA ; B = SMB_BMC_MM6_SDA

(kicad_pcb
	(version 20260206)
	(generator "pcbnew")
	(generator_version "10.0")
	(general
		(thickness 1.6)
		(legacy_teardrops no)
	)
	(paper "A4")
	(title_block
		(title "12092022_DA0F0TMDCD0_F0T_Management_Board_D_brd_V3_OCP.brd")
		(comment 1 "Grand Teton / footprints 1355-1356 of 1440")
	)
	(layers
		(0 "F.Cu" signal "TOP")
		(4 "In1.Cu" signal "GND")
		(6 "In2.Cu" signal "IN1")
		(8 "In3.Cu" signal "GND1")
		(10 "In4.Cu" signal "IN2")
		(12 "In5.Cu" signal "VCC")
		(14 "In6.Cu" signal "VCC1")
		(16 "In7.Cu" signal "IN3")
		(18 "In8.Cu" signal "GND2")
		(20 "In9.Cu" signal "IN4")
		(22 "In10.Cu" signal "GND3")
		(2 "B.Cu" signal "BOTTOM")
		(9 "F.Adhes" user "F.Adhesive")
		(11 "B.Adhes" user "B.Adhesive")
		(13 "F.Paste" user "Package Geometry/Pastemask Top")
		(15 "B.Paste" user "Package Geometry/Pastemask Bottom")
		(5 "F.SilkS" user "Ref Des/Silkscreen Top")
		(7 "B.SilkS" user "Ref Des/Silkscreen Bottom")
		(1 "F.Mask" user "Board Geometry/Soldermask Top")
		(3 "B.Mask" user "Board Geometry/Soldermask Bottom")
		(17 "Dwgs.User" user "User.Drawings")
		(19 "Cmts.User" user "User.Comments")
		(21 "Eco1.User" user "User.Eco1")
		(23 "Eco2.User" user "User.Eco2")
		(25 "Edge.Cuts" user "Board Geometry/Outline")
		(27 "Margin" user)
		(31 "F.CrtYd" user "Package Geometry/Place Bound Top")
		(29 "B.CrtYd" user "Package Geometry/Place Bound Bottom")
		(35 "F.Fab" user "Ref Des/Assembly Top")
		(33 "B.Fab" user "Ref Des/Assembly Bottom")
	)
	(footprint ""
		(layer "B.Cu")
		(at 58.547 -34.671 90)
		(property "Reference" "R143"
			(at 0 0 90)
			(layer "B.SilkS")
			(hide yes)
			(effects
				(font
					(size 1.27 1.27)
				)
				(justify mirror)
			)
		)
		(property "Value" ""
			(at 0 0 90)
			(layer "B.Fab")
			(effects
				(font
					(size 1.27 1.27)
				)
				(justify mirror)
			)
		)
		(duplicate_pad_numbers_are_jumpers no)
		(fp_line
			(start 0.7874 -0.4064)
			(end -0.7874 -0.4064)
			(stroke
				(width 0.1524)
				(type default)
			)
			(layer "B.SilkS")
		)
		(fp_line
			(start -0.7874 -0.4064)
			(end -0.7874 0.4064)
			(stroke
				(width 0.1524)
				(type default)
			)
			(layer "B.SilkS")
		)
		(fp_line
			(start 0.7874 0.4064)
			(end 0.7874 -0.4064)
			(stroke
				(width 0.1524)
				(type default)
			)
			(layer "B.SilkS")
		)
		(fp_line
			(start -0.7874 0.4064)
			(end 0.7874 0.4064)
			(stroke
				(width 0.1524)
				(type default)
			)
			(layer "B.SilkS")
		)
		(fp_line
			(start 0.67945 -0.305054)
			(end 0.12065 -0.305054)
			(stroke
				(width 0.1)
				(type default)
			)
			(layer "B.Fab")
		)
		(fp_line
			(start 0.12065 -0.305054)
			(end 0.12065 -0.2794)
			(stroke
				(width 0.1)
				(type default)
			)
			(layer "B.Fab")
		)
		(fp_line
			(start -0.12065 -0.3048)
			(end -0.67945 -0.3048)
			(stroke
				(width 0.1)
				(type default)
			)
			(layer "B.Fab")
		)
		(fp_line
			(start -0.67945 -0.3048)
			(end -0.67945 0.3048)
			(stroke
				(width 0.1)
				(type default)
			)
			(layer "B.Fab")
		)
		(fp_line
			(start 0.12065 -0.2794)
			(end -0.12065 -0.2794)
			(stroke
				(width 0.1)
				(type default)
			)
			(layer "B.Fab")
		)
		(fp_line
			(start -0.12065 -0.2794)
			(end -0.12065 -0.3048)
			(stroke
				(width 0.1)
				(type default)
			)
			(layer "B.Fab")
		)
		(fp_line
			(start 0.12065 0.2794)
			(end 0.12065 0.3048)
			(stroke
				(width 0.1)
				(type default)
			)
			(layer "B.Fab")
		)
		(fp_line
			(start -0.120396 0.2794)
			(end 0.12065 0.2794)
			(stroke
				(width 0.1)
				(type default)
			)
			(layer "B.Fab")
		)
		(fp_line
			(start 0.67945 0.3048)
			(end 0.67945 -0.305054)
			(stroke
				(width 0.1)
				(type default)
			)
			(layer "B.Fab")
		)
		(fp_line
			(start 0.12065 0.3048)
			(end 0.67945 0.3048)
			(stroke
				(width 0.1)
				(type default)
			)
			(layer "B.Fab")
		)
		(fp_line
			(start -0.120396 0.3048)
			(end -0.120396 0.2794)
			(stroke
				(width 0.1)
				(type default)
			)
			(layer "B.Fab")
		)
		(fp_line
			(start -0.67945 0.3048)
			(end -0.120396 0.3048)
			(stroke
				(width 0.1)
				(type default)
			)
			(layer "B.Fab")
		)
		(pad "1" smd circle
			(at 0.40005 0 270)
			(size 0 0)
			(layers "B.Cu" "B.Mask" "B.Paste")
			(net "SMB_BMC_MM6_R_SDA")
		)
		(pad "2" smd circle
			(at -0.40005 0 270)
			(size 0 0)
			(layers "B.Cu" "B.Mask" "B.Paste")
			(net "SMB_BMC_MM6_SDA")
		)
	)
	(footprint ""
		(layer "B.Cu")
		(at 29.972 -100.838 180)
		(property "Reference" "C145"
			(at 0 0 0)
			(layer "B.SilkS")
			(hide yes)
			(effects
				(font
					(size 1.27 1.27)
				)
				(justify mirror)
			)
		)
		(property "Value" ""
			(at 0 0 0)
			(layer "B.Fab")
			(effects
				(font
					(size 1.27 1.27)
				)
				(justify mirror)
			)
		)
		(duplicate_pad_numbers_are_jumpers no)
		(fp_line
			(start 0.7874 0.4064)
			(end 0.7874 -0.4064)
			(stroke
				(width 0.1524)
				(type default)
			)
			(layer "B.SilkS")
		)
		(fp_line
			(start 0.7874 -0.4064)
			(end -0.7874 -0.4064)
			(stroke
				(width 0.1524)
				(type default)
			)
			(layer "B.SilkS")
		)
		(fp_line
			(start -0.7874 0.4064)
			(end 0.7874 0.4064)
			(stroke
				(width 0.1524)
				(type default)
			)
			(layer "B.SilkS")
		)
		(fp_line
			(start -0.7874 -0.4064)
			(end -0.7874 0.4064)
			(stroke
				(width 0.1524)
				(type default)
			)
			(layer "B.SilkS")
		)
		(fp_line
			(start 0.67945 0.3048)
			(end 0.67945 -0.305054)
			(stroke
				(width 0.1)
				(type default)
			)
			(layer "B.Fab")
		)
		(fp_line
			(start 0.67945 -0.305054)
			(end 0.12065 -0.305054)
			(stroke
				(width 0.1)
				(type default)
			)
			(layer "B.Fab")
		)
		(fp_line
			(start 0.12065 0.3048)
			(end 0.67945 0.3048)
			(stroke
				(width 0.1)
				(type default)
			)
			(layer "B.Fab")
		)
		(fp_line
			(start 0.12065 0.2794)
			(end 0.12065 0.3048)
			(stroke
				(width 0.1)
				(type default)
			)
			(layer "B.Fab")
		)
		(fp_line
			(start 0.12065 -0.2794)
			(end -0.12065 -0.2794)
			(stroke
				(width 0.1)
				(type default)
			)
			(layer "B.Fab")
		)
		(fp_line
			(start 0.12065 -0.305054)
			(end 0.12065 -0.2794)
			(stroke
				(width 0.1)
				(type default)
			)
			(layer "B.Fab")
		)
		(fp_line
			(start -0.120396 0.3048)
			(end -0.120396 0.2794)
			(stroke
				(width 0.1)
				(type default)
			)
			(layer "B.Fab")
		)
		(fp_line
			(start -0.120396 0.2794)
			(end 0.12065 0.2794)
			(stroke
				(width 0.1)
				(type default)
			)
			(layer "B.Fab")
		)
		(fp_line
			(start -0.12065 -0.2794)
			(end -0.12065 -0.3048)
			(stroke
				(width 0.1)
				(type default)
			)
			(layer "B.Fab")
		)
		(fp_line
			(start -0.12065 -0.3048)
			(end -0.67945 -0.3048)
			(stroke
				(width 0.1)
				(type default)
			)
			(layer "B.Fab")
		)
		(fp_line
			(start -0.67945 0.3048)
			(end -0.120396 0.3048)
			(stroke
				(width 0.1)
				(type default)
			)
			(layer "B.Fab")
		)
		(fp_line
			(start -0.67945 -0.3048)
			(end -0.67945 0.3048)
			(stroke
				(width 0.1)
				(type default)
			)
			(layer "B.Fab")
		)
		(pad "1" smd circle
			(at 0.40005 0)
			(size 0 0)
			(layers "B.Cu" "B.Mask" "B.Paste")
			(net "P3V3_AUX")
		)
		(pad "2" smd circle
			(at -0.40005 0)
			(size 0 0)
			(layers "B.Cu" "B.Mask" "B.Paste")
			(net "GND")
		)
	)
)
